(kicad_pcb
	(version 20260206)
	(generator "pcbnew")
	(generator_version "10.0")
	(general
		(thickness 1.6)
		(legacy_teardrops no)
	)
	(paper "A4")
	(title_block
		(title "01162023_DA0F0TEBIF0_F0T_Expander_BD_F_brd_V02_OCP.brd")
		(comment 1 "Grand Teton / footprints 652-660 of 9728")
	)
	(layers
		(0 "F.Cu" signal "TOP")
		(4 "In1.Cu" signal "GND")
		(6 "In2.Cu" signal "VCC")
		(8 "In3.Cu" signal "VCC1")
		(10 "In4.Cu" signal "GND1")
		(12 "In5.Cu" signal "IN1")
		(14 "In6.Cu" signal "GND2")
		(16 "In7.Cu" signal "IN2")
		(18 "In8.Cu" signal "GND3")
		(20 "In9.Cu" signal "IN3")
		(22 "In10.Cu" signal "GND4")
		(24 "In11.Cu" signal "IN4")
		(26 "In12.Cu" signal "GND5")
		(28 "In13.Cu" signal "IN5")
		(30 "In14.Cu" signal "GND6")
		(32 "In15.Cu" signal "IN6")
		(34 "In16.Cu" signal "GND7")
		(2 "B.Cu" signal "BOTTOM")
		(9 "F.Adhes" user "F.Adhesive")
		(11 "B.Adhes" user "B.Adhesive")
		(13 "F.Paste" user "Package Geometry/Pastemask Top")
		(15 "B.Paste" user "Package Geometry/Pastemask Bottom")
		(5 "F.SilkS" user "Ref Des/Silkscreen Top")
		(7 "B.SilkS" user "Ref Des/Silkscreen Bottom")
		(1 "F.Mask" user "Board Geometry/Soldermask Top")
		(3 "B.Mask" user "Board Geometry/Soldermask Bottom")
		(17 "Dwgs.User" user "User.Drawings")
		(19 "Cmts.User" user "User.Comments")
		(21 "Eco1.User" user "User.Eco1")
		(23 "Eco2.User" user "User.Eco2")
		(25 "Edge.Cuts" user "Board Geometry/Outline")
		(27 "Margin" user)
		(31 "F.CrtYd" user "Package Geometry/Place Bound Top")
		(29 "B.CrtYd" user "Package Geometry/Place Bound Bottom")
		(35 "F.Fab" user "Ref Des/Assembly Top")
		(33 "B.Fab" user "Ref Des/Assembly Bottom")
	)
	(footprint ""
		(layer "F.Cu")
		(at 271.03197 -147.969224 90)
		(property "Reference" "C906"
			(at 0 0 90)
			(layer "F.SilkS")
			(hide yes)
			(effects
				(font
					(size 1.27 1.27)
				)
			)
		)
		(property "Value" ""
			(at 0 0 90)
			(layer "F.Fab")
			(effects
				(font
					(size 1.27 1.27)
				)
			)
		)
		(duplicate_pad_numbers_are_jumpers no)
		(fp_line
			(start 1.524 -0.762)
			(end 1.524 0.762)
			(stroke
				(width 0.1524)
				(type default)
			)
			(layer "F.SilkS")
		)
		(fp_line
			(start -1.524 -0.762)
			(end 1.524 -0.762)
			(stroke
				(width 0.1524)
				(type default)
			)
			(layer "F.SilkS")
		)
		(fp_line
			(start 1.524 0.762)
			(end -1.524 0.762)
			(stroke
				(width 0.1524)
				(type default)
			)
			(layer "F.SilkS")
		)
		(fp_line
			(start -1.524 0.762)
			(end -1.524 -0.762)
			(stroke
				(width 0.1524)
				(type default)
			)
			(layer "F.SilkS")
		)
		(fp_line
			(start 1.1049 -0.724916)
			(end -1.1049 -0.724916)
			(stroke
				(width 0.1)
				(type default)
			)
			(layer "F.Fab")
		)
		(fp_line
			(start -1.1049 -0.724916)
			(end -1.1049 0.724916)
			(stroke
				(width 0.1)
				(type default)
			)
			(layer "F.Fab")
		)
		(fp_line
			(start 1.1049 0.724916)
			(end 1.1049 -0.724916)
			(stroke
				(width 0.1)
				(type default)
			)
			(layer "F.Fab")
		)
		(fp_line
			(start -1.1049 0.724916)
			(end 1.1049 0.724916)
			(stroke
				(width 0.1)
				(type default)
			)
			(layer "F.Fab")
		)
		(pad "1" smd rect
			(at -0.889 0 270)
			(size 1.016 1.27)
			(layers "F.Cu" "F.Mask" "F.Paste")
			(net "P12V_NIC4")
		)
		(pad "2" smd rect
			(at 0.889 0 270)
			(size 1.016 1.27)
			(layers "F.Cu" "F.Mask" "F.Paste")
			(net "GND")
		)
	)
	(footprint ""
		(layer "F.Cu")
		(at 115.279424 -170.951652)
		(property "Reference" "PC25"
			(at 0 0 0)
			(layer "F.SilkS")
			(hide yes)
			(effects
				(font
					(size 1.27 1.27)
				)
			)
		)
		(property "Value" ""
			(at 0 0 0)
			(layer "F.Fab")
			(effects
				(font
					(size 1.27 1.27)
				)
			)
		)
		(duplicate_pad_numbers_are_jumpers no)
		(fp_line
			(start -3.400044 -2.146046)
			(end -3.400044 -0.9398)
			(stroke
				(width 0.1524)
				(type default)
			)
			(layer "F.SilkS")
		)
		(fp_line
			(start -3.400044 2.146046)
			(end -3.400044 0.9398)
			(stroke
				(width 0.1524)
				(type default)
			)
			(layer "F.SilkS")
		)
		(fp_line
			(start -2.146046 -3.400044)
			(end -3.400044 -2.146046)
			(stroke
				(width 0.1524)
				(type default)
			)
			(layer "F.SilkS")
		)
		(fp_line
			(start -2.146046 3.400044)
			(end -3.400044 2.146046)
			(stroke
				(width 0.1524)
				(type default)
			)
			(layer "F.SilkS")
		)
		(fp_line
			(start 3.400044 -3.400044)
			(end -2.146046 -3.400044)
			(stroke
				(width 0.1524)
				(type default)
			)
			(layer "F.SilkS")
		)
		(fp_line
			(start 3.400044 -0.9398)
			(end 3.400044 -3.400044)
			(stroke
				(width 0.1524)
				(type default)
			)
			(layer "F.SilkS")
		)
		(fp_line
			(start 3.400044 0.9398)
			(end 3.400044 3.400044)
			(stroke
				(width 0.1524)
				(type default)
			)
			(layer "F.SilkS")
		)
		(fp_line
			(start 3.400044 3.400044)
			(end -2.146046 3.400044)
			(stroke
				(width 0.1524)
				(type default)
			)
			(layer "F.SilkS")
		)
		(fp_line
			(start -3.400044 -3.400044)
			(end -3.400044 3.400044)
			(stroke
				(width 0.1)
				(type default)
			)
			(layer "F.Fab")
		)
		(fp_line
			(start -3.400044 3.400044)
			(end 3.400044 3.400044)
			(stroke
				(width 0.1)
				(type default)
			)
			(layer "F.Fab")
		)
		(fp_line
			(start 3.400044 -3.400044)
			(end -3.400044 -3.400044)
			(stroke
				(width 0.1)
				(type default)
			)
			(layer "F.Fab")
		)
		(fp_line
			(start 3.400044 3.400044)
			(end 3.400044 -3.400044)
			(stroke
				(width 0.1)
				(type default)
			)
			(layer "F.Fab")
		)
		(pad "1" smd rect
			(at -2.70002 0 270)
			(size 1.6002 3.5052)
			(layers "F.Cu" "F.Mask" "F.Paste")
			(net "SW_P12V_P3V3_AUX_FLT")
		)
		(pad "2" smd rect
			(at 2.70002 0 270)
			(size 1.6002 3.5052)
			(layers "F.Cu" "F.Mask" "F.Paste")
			(net "GND")
		)
	)
	(footprint ""
		(layer "F.Cu")
		(at 270.799814 -150.263352 180)
		(property "Reference" "R219"
			(at 0 0 180)
			(layer "F.SilkS")
			(hide yes)
			(effects
				(font
					(size 1.27 1.27)
				)
			)
		)
		(property "Value" ""
			(at 0 0 180)
			(layer "F.Fab")
			(effects
				(font
					(size 1.27 1.27)
				)
			)
		)
		(duplicate_pad_numbers_are_jumpers no)
		(fp_line
			(start 0.7874 0.4064)
			(end -0.7874 0.4064)
			(stroke
				(width 0.1524)
				(type default)
			)
			(layer "F.SilkS")
		)
		(fp_line
			(start 0.7874 -0.4064)
			(end 0.7874 0.4064)
			(stroke
				(width 0.1524)
				(type default)
			)
			(layer "F.SilkS")
		)
		(fp_line
			(start -0.7874 0.4064)
			(end -0.7874 -0.4064)
			(stroke
				(width 0.1524)
				(type default)
			)
			(layer "F.SilkS")
		)
		(fp_line
			(start -0.7874 -0.4064)
			(end 0.7874 -0.4064)
			(stroke
				(width 0.1524)
				(type default)
			)
			(layer "F.SilkS")
		)
		(fp_line
			(start 0.67945 0.3048)
			(end 0.120396 0.3048)
			(stroke
				(width 0.1)
				(type default)
			)
			(layer "F.Fab")
		)
		(fp_line
			(start 0.67945 -0.3048)
			(end 0.67945 0.3048)
			(stroke
				(width 0.1)
				(type default)
			)
			(layer "F.Fab")
		)
		(fp_line
			(start 0.12065 -0.2794)
			(end 0.12065 -0.3048)
			(stroke
				(width 0.1)
				(type default)
			)
			(layer "F.Fab")
		)
		(fp_line
			(start 0.12065 -0.3048)
			(end 0.67945 -0.3048)
			(stroke
				(width 0.1)
				(type default)
			)
			(layer "F.Fab")
		)
		(fp_line
			(start 0.120396 0.3048)
			(end 0.120396 0.2794)
			(stroke
				(width 0.1)
				(type default)
			)
			(layer "F.Fab")
		)
		(fp_line
			(start 0.120396 0.2794)
			(end -0.12065 0.2794)
			(stroke
				(width 0.1)
				(type default)
			)
			(layer "F.Fab")
		)
		(fp_line
			(start -0.12065 0.3048)
			(end -0.67945 0.3048)
			(stroke
				(width 0.1)
				(type default)
			)
			(layer "F.Fab")
		)
		(fp_line
			(start -0.12065 0.2794)
			(end -0.12065 0.3048)
			(stroke
				(width 0.1)
				(type default)
			)
			(layer "F.Fab")
		)
		(fp_line
			(start -0.12065 -0.2794)
			(end 0.12065 -0.2794)
			(stroke
				(width 0.1)
				(type default)
			)
			(layer "F.Fab")
		)
		(fp_line
			(start -0.12065 -0.305054)
			(end -0.12065 -0.2794)
			(stroke
				(width 0.1)
				(type default)
			)
			(layer "F.Fab")
		)
		(fp_line
			(start -0.67945 0.3048)
			(end -0.67945 -0.305054)
			(stroke
				(width 0.1)
				(type default)
			)
			(layer "F.Fab")
		)
		(fp_line
			(start -0.67945 -0.305054)
			(end -0.12065 -0.305054)
			(stroke
				(width 0.1)
				(type default)
			)
			(layer "F.Fab")
		)
		(pad "1" smd circle
			(at -0.40005 0 180)
			(size 0 0)
			(layers "F.Cu" "F.Mask" "F.Paste")
			(net "NCSI_NIC4_CRS_DV")
		)
		(pad "2" smd circle
			(at 0.40005 0 180)
			(size 0 0)
			(layers "F.Cu" "F.Mask" "F.Paste")
			(net "GND")
		)
	)
	(footprint ""
		(layer "F.Cu")
		(at 271.480534 -110.088934)
		(property "Reference" "C473"
			(at 0 0 0)
			(layer "F.SilkS")
			(hide yes)
			(effects
				(font
					(size 1.27 1.27)
				)
			)
		)
		(property "Value" ""
			(at 0 0 0)
			(layer "F.Fab")
			(effects
				(font
					(size 1.27 1.27)
				)
			)
		)
		(duplicate_pad_numbers_are_jumpers no)
		(fp_line
			(start -0.299974 -0.150114)
			(end 0.299974 -0.150114)
			(stroke
				(width 0.1)
				(type default)
			)
			(layer "F.Fab")
		)
		(fp_line
			(start -0.299974 0.150114)
			(end -0.299974 -0.150114)
			(stroke
				(width 0.1)
				(type default)
			)
			(layer "F.Fab")
		)
		(fp_line
			(start 0.299974 -0.150114)
			(end 0.299974 0.150114)
			(stroke
				(width 0.1)
				(type default)
			)
			(layer "F.Fab")
		)
		(fp_line
			(start 0.299974 0.150114)
			(end -0.299974 0.150114)
			(stroke
				(width 0.1)
				(type default)
			)
			(layer "F.Fab")
		)
		(pad "1" smd rect
			(at -0.2667 0)
			(size 0.3048 0.381)
			(layers "F.Cu" "F.Mask" "F.Paste")
			(net "P5E_PEX2_STN1_TX_DP<22>")
		)
		(pad "2" smd rect
			(at 0.2667 0)
			(size 0.3048 0.381)
			(layers "F.Cu" "F.Mask" "F.Paste")
			(net "P5E_PEX2_STN1_TX_C_DP<22>")
		)
	)
	(footprint ""
		(layer "F.Cu")
		(at 383.598674 -137.259314 -90)
		(property "Reference" "C944"
			(at 0 0 270)
			(layer "F.SilkS")
			(hide yes)
			(effects
				(font
					(size 1.27 1.27)
				)
			)
		)
		(property "Value" ""
			(at 0 0 270)
			(layer "F.Fab")
			(effects
				(font
					(size 1.27 1.27)
				)
			)
		)
		(duplicate_pad_numbers_are_jumpers no)
		(fp_line
			(start -0.7874 0.4064)
			(end -0.7874 -0.4064)
			(stroke
				(width 0.1524)
				(type default)
			)
			(layer "F.SilkS")
		)
		(fp_line
			(start 0.7874 0.4064)
			(end -0.7874 0.4064)
			(stroke
				(width 0.1524)
				(type default)
			)
			(layer "F.SilkS")
		)
		(fp_line
			(start -0.7874 -0.4064)
			(end 0.7874 -0.4064)
			(stroke
				(width 0.1524)
				(type default)
			)
			(layer "F.SilkS")
		)
		(fp_line
			(start 0.7874 -0.4064)
			(end 0.7874 0.4064)
			(stroke
				(width 0.1524)
				(type default)
			)
			(layer "F.SilkS")
		)
		(fp_line
			(start -0.67945 0.3048)
			(end -0.67945 -0.305054)
			(stroke
				(width 0.1)
				(type default)
			)
			(layer "F.Fab")
		)
		(fp_line
			(start -0.12065 0.3048)
			(end -0.67945 0.3048)
			(stroke
				(width 0.1)
				(type default)
			)
			(layer "F.Fab")
		)
		(fp_line
			(start 0.120396 0.3048)
			(end 0.120396 0.2794)
			(stroke
				(width 0.1)
				(type default)
			)
			(layer "F.Fab")
		)
		(fp_line
			(start 0.67945 0.3048)
			(end 0.120396 0.3048)
			(stroke
				(width 0.1)
				(type default)
			)
			(layer "F.Fab")
		)
		(fp_line
			(start -0.12065 0.2794)
			(end -0.12065 0.3048)
			(stroke
				(width 0.1)
				(type default)
			)
			(layer "F.Fab")
		)
		(fp_line
			(start 0.120396 0.2794)
			(end -0.12065 0.2794)
			(stroke
				(width 0.1)
				(type default)
			)
			(layer "F.Fab")
		)
		(fp_line
			(start -0.12065 -0.2794)
			(end 0.12065 -0.2794)
			(stroke
				(width 0.1)
				(type default)
			)
			(layer "F.Fab")
		)
		(fp_line
			(start 0.12065 -0.2794)
			(end 0.12065 -0.3048)
			(stroke
				(width 0.1)
				(type default)
			)
			(layer "F.Fab")
		)
		(fp_line
			(start 0.12065 -0.3048)
			(end 0.67945 -0.3048)
			(stroke
				(width 0.1)
				(type default)
			)
			(layer "F.Fab")
		)
		(fp_line
			(start 0.67945 -0.3048)
			(end 0.67945 0.3048)
			(stroke
				(width 0.1)
				(type default)
			)
			(layer "F.Fab")
		)
		(fp_line
			(start -0.67945 -0.305054)
			(end -0.12065 -0.305054)
			(stroke
				(width 0.1)
				(type default)
			)
			(layer "F.Fab")
		)
		(fp_line
			(start -0.12065 -0.305054)
			(end -0.12065 -0.2794)
			(stroke
				(width 0.1)
				(type default)
			)
			(layer "F.Fab")
		)
		(pad "1" smd circle
			(at -0.40005 0 270)
			(size 0 0)
			(layers "F.Cu" "F.Mask" "F.Paste")
			(net "P3V3_NIC6")
		)
		(pad "2" smd circle
			(at 0.40005 0 270)
			(size 0 0)
			(layers "F.Cu" "F.Mask" "F.Paste")
			(net "GND")
		)
	)
	(footprint ""
		(layer "F.Cu")
		(at 242.730528 -146.099276 180)
		(property "Reference" "PC802"
			(at 0 0 180)
			(layer "F.SilkS")
			(hide yes)
			(effects
				(font
					(size 1.27 1.27)
				)
			)
		)
		(property "Value" ""
			(at 0 0 180)
			(layer "F.Fab")
			(effects
				(font
					(size 1.27 1.27)
				)
			)
		)
		(duplicate_pad_numbers_are_jumpers no)
		(fp_line
			(start 1.524 0.762)
			(end -1.524 0.762)
			(stroke
				(width 0.1524)
				(type default)
			)
			(layer "F.SilkS")
		)
		(fp_line
			(start 1.524 -0.762)
			(end 1.524 0.762)
			(stroke
				(width 0.1524)
				(type default)
			)
			(layer "F.SilkS")
		)
		(fp_line
			(start -1.524 0.762)
			(end -1.524 -0.762)
			(stroke
				(width 0.1524)
				(type default)
			)
			(layer "F.SilkS")
		)
		(fp_line
			(start -1.524 -0.762)
			(end 1.524 -0.762)
			(stroke
				(width 0.1524)
				(type default)
			)
			(layer "F.SilkS")
		)
		(fp_line
			(start 1.1049 0.724916)
			(end 1.1049 -0.724916)
			(stroke
				(width 0.1)
				(type default)
			)
			(layer "F.Fab")
		)
		(fp_line
			(start 1.1049 -0.724916)
			(end -1.1049 -0.724916)
			(stroke
				(width 0.1)
				(type default)
			)
			(layer "F.Fab")
		)
		(fp_line
			(start -1.1049 0.724916)
			(end 1.1049 0.724916)
			(stroke
				(width 0.1)
				(type default)
			)
			(layer "F.Fab")
		)
		(fp_line
			(start -1.1049 -0.724916)
			(end -1.1049 0.724916)
			(stroke
				(width 0.1)
				(type default)
			)
			(layer "F.Fab")
		)
		(pad "1" smd rect
			(at -0.889 0)
			(size 1.016 1.27)
			(layers "F.Cu" "F.Mask" "F.Paste")
			(net "P12V_NIC4_R")
		)
		(pad "2" smd rect
			(at 0.889 0)
			(size 1.016 1.27)
			(layers "F.Cu" "F.Mask" "F.Paste")
			(net "GND")
		)
	)
	(footprint ""
		(layer "F.Cu")
		(at 261.07517 -63.086234)
		(property "Reference" "R5999"
			(at 0 0 0)
			(layer "F.SilkS")
			(hide yes)
			(effects
				(font
					(size 1.27 1.27)
				)
			)
		)
		(property "Value" ""
			(at 0 0 0)
			(layer "F.Fab")
			(effects
				(font
					(size 1.27 1.27)
				)
			)
		)
		(duplicate_pad_numbers_are_jumpers no)
		(fp_line
			(start -0.7874 -0.4064)
			(end 0.7874 -0.4064)
			(stroke
				(width 0.1524)
				(type default)
			)
			(layer "F.SilkS")
		)
		(fp_line
			(start -0.7874 0.4064)
			(end -0.7874 -0.4064)
			(stroke
				(width 0.1524)
				(type default)
			)
			(layer "F.SilkS")
		)
		(fp_line
			(start 0.7874 -0.4064)
			(end 0.7874 0.4064)
			(stroke
				(width 0.1524)
				(type default)
			)
			(layer "F.SilkS")
		)
		(fp_line
			(start 0.7874 0.4064)
			(end -0.7874 0.4064)
			(stroke
				(width 0.1524)
				(type default)
			)
			(layer "F.SilkS")
		)
		(fp_line
			(start -0.67945 -0.305054)
			(end -0.12065 -0.305054)
			(stroke
				(width 0.1)
				(type default)
			)
			(layer "F.Fab")
		)
		(fp_line
			(start -0.67945 0.3048)
			(end -0.67945 -0.305054)
			(stroke
				(width 0.1)
				(type default)
			)
			(layer "F.Fab")
		)
		(fp_line
			(start -0.12065 -0.305054)
			(end -0.12065 -0.2794)
			(stroke
				(width 0.1)
				(type default)
			)
			(layer "F.Fab")
		)
		(fp_line
			(start -0.12065 -0.2794)
			(end 0.12065 -0.2794)
			(stroke
				(width 0.1)
				(type default)
			)
			(layer "F.Fab")
		)
		(fp_line
			(start -0.12065 0.2794)
			(end -0.12065 0.3048)
			(stroke
				(width 0.1)
				(type default)
			)
			(layer "F.Fab")
		)
		(fp_line
			(start -0.12065 0.3048)
			(end -0.67945 0.3048)
			(stroke
				(width 0.1)
				(type default)
			)
			(layer "F.Fab")
		)
		(fp_line
			(start 0.120396 0.2794)
			(end -0.12065 0.2794)
			(stroke
				(width 0.1)
				(type default)
			)
			(layer "F.Fab")
		)
		(fp_line
			(start 0.120396 0.3048)
			(end 0.120396 0.2794)
			(stroke
				(width 0.1)
				(type default)
			)
			(layer "F.Fab")
		)
		(fp_line
			(start 0.12065 -0.3048)
			(end 0.67945 -0.3048)
			(stroke
				(width 0.1)
				(type default)
			)
			(layer "F.Fab")
		)
		(fp_line
			(start 0.12065 -0.2794)
			(end 0.12065 -0.3048)
			(stroke
				(width 0.1)
				(type default)
			)
			(layer "F.Fab")
		)
		(fp_line
			(start 0.67945 -0.3048)
			(end 0.67945 0.3048)
			(stroke
				(width 0.1)
				(type default)
			)
			(layer "F.Fab")
		)
		(fp_line
			(start 0.67945 0.3048)
			(end 0.120396 0.3048)
			(stroke
				(width 0.1)
				(type default)
			)
			(layer "F.Fab")
		)
		(pad "1" smd circle
			(at -0.40005 0)
			(size 0 0)
			(layers "F.Cu" "F.Mask" "F.Paste")
			(net "P12V_SSD9_R")
		)
		(pad "2" smd circle
			(at 0.40005 0)
			(size 0 0)
			(layers "F.Cu" "F.Mask" "F.Paste")
			(net "P12V_SSD9_PG_G1")
		)
	)
	(footprint ""
		(layer "F.Cu")
		(at 478.67189 -547.47541 180)
		(property "Reference" "SCREW_SSD15_2"
			(at -5.6007 -1.402334 0)
			(unlocked yes)
			(layer "B.SilkS")
			(effects
				(font
					(size 0.7874 0.5842)
					(thickness 0.1524)
				)
				(justify mirror)
			)
		)
		(property "Value" ""
			(at 0 0 180)
			(layer "F.Fab")
			(effects
				(font
					(size 1.27 1.27)
				)
			)
		)
		(duplicate_pad_numbers_are_jumpers no)
		(pad "1" thru_hole circle
			(at 0 0 180)
			(size 0.4572 0.4572)
			(drill 0.2032)
			(layers "*.Cu" "*.Mask")
			(remove_unused_layers no)
			(net "Net_9143")
			(clearance 0.127)
			(thermal_gap 0.127)
			(padstack
				(mode front_inner_back)
				(layer "Inner"
					(shape circle)
					(size 0.4572 0.4572)
					(clearance 0.127)
				)
				(layer "B.Cu"
					(shape circle)
					(size 0.508 0.508)
					(clearance 0.1016)
				)
			)
		)
	)
	(footprint ""
		(layer "F.Cu")
		(at 322.718684 -350.098614 90)
		(property "Reference" "C560"
			(at 0 0 90)
			(layer "F.SilkS")
			(hide yes)
			(effects
				(font
					(size 1.27 1.27)
				)
			)
		)
		(property "Value" ""
			(at 0 0 90)
			(layer "F.Fab")
			(effects
				(font
					(size 1.27 1.27)
				)
			)
		)
		(duplicate_pad_numbers_are_jumpers no)
		(fp_line
			(start 0.299974 -0.150114)
			(end 0.299974 0.150114)
			(stroke
				(width 0.1)
				(type default)
			)
			(layer "F.Fab")
		)
		(fp_line
			(start -0.299974 -0.150114)
			(end 0.299974 -0.150114)
			(stroke
				(width 0.1)
				(type default)
			)
			(layer "F.Fab")
		)
		(fp_line
			(start 0.299974 0.150114)
			(end -0.299974 0.150114)
			(stroke
				(width 0.1)
				(type default)
			)
			(layer "F.Fab")
		)
		(fp_line
			(start -0.299974 0.150114)
			(end -0.299974 -0.150114)
			(stroke
				(width 0.1)
				(type default)
			)
			(layer "F.Fab")
		)
		(pad "1" smd rect
			(at -0.2667 0 90)
			(size 0.3048 0.381)
			(layers "F.Cu" "F.Mask" "F.Paste")
			(net "P5E_PEX2_STN6_TX_DN<107>")
		)
		(pad "2" smd rect
			(at 0.2667 0 90)
			(size 0.3048 0.381)
			(layers "F.Cu" "F.Mask" "F.Paste")
			(net "P5E_PEX2_STN6_TX_C_DN<107>")
		)
	)
)
